(kicad_pcb
	(version 20260206)
	(generator "pcbnew")
	(generator_version "10.0")
	(general
		(thickness 1.6)
		(legacy_teardrops no)
	)
	(paper "A4")
	(title_block
		(title "04192023_DAF0TMB3IC0_F0TG_MB_C_brd_V02_OCP.brd")
		(comment 1 "Grand Teton / footprints 7839-7845 of 8354")
	)
	(layers
		(0 "F.Cu" signal "TOP")
		(4 "In1.Cu" signal "GND")
		(6 "In2.Cu" signal "IN1")
		(8 "In3.Cu" signal "GND1")
		(10 "In4.Cu" signal "IN2")
		(12 "In5.Cu" signal "GND2")
		(14 "In6.Cu" signal "IN3")
		(16 "In7.Cu" signal "GND3")
		(18 "In8.Cu" signal "VCC")
		(20 "In9.Cu" signal "VCC1")
		(22 "In10.Cu" signal "GND4")
		(24 "In11.Cu" signal "IN4")
		(26 "In12.Cu" signal "GND5")
		(28 "In13.Cu" signal "IN5")
		(30 "In14.Cu" signal "GND6")
		(32 "In15.Cu" signal "IN6")
		(34 "In16.Cu" signal "GND7")
		(2 "B.Cu" signal "BOTTOM")
		(9 "F.Adhes" user "F.Adhesive")
		(11 "B.Adhes" user "B.Adhesive")
		(13 "F.Paste" user "Package Geometry/Pastemask Top")
		(15 "B.Paste" user "Package Geometry/Pastemask Bottom")
		(5 "F.SilkS" user "Ref Des/Silkscreen Top")
		(7 "B.SilkS" user "Ref Des/Silkscreen Bottom")
		(1 "F.Mask" user "Board Geometry/Soldermask Top")
		(3 "B.Mask" user "Board Geometry/Soldermask Bottom")
		(17 "Dwgs.User" user "User.Drawings")
		(19 "Cmts.User" user "User.Comments")
		(21 "Eco1.User" user "User.Eco1")
		(23 "Eco2.User" user "User.Eco2")
		(25 "Edge.Cuts" user "Board Geometry/Outline")
		(27 "Margin" user)
		(31 "F.CrtYd" user "Package Geometry/Place Bound Top")
		(29 "B.CrtYd" user "Package Geometry/Place Bound Bottom")
		(35 "F.Fab" user "Ref Des/Assembly Top")
		(33 "B.Fab" user "Ref Des/Assembly Bottom")
	)
	(footprint ""
		(layer "B.Cu")
		(at 119.59717 -381.11303 180)
		(property "Reference" "C7029"
			(at -1.78308 -3.179572 0)
			(unlocked yes)
			(layer "B.SilkS")
			(effects
				(font
					(size 0.7874 0.5842)
					(thickness 0.1524)
				)
				(justify left mirror)
			)
		)
		(property "Value" ""
			(at 0 0 0)
			(layer "B.Fab")
			(effects
				(font
					(size 1.27 1.27)
				)
				(justify mirror)
			)
		)
		(duplicate_pad_numbers_are_jumpers no)
		(fp_line
			(start 4.84378 -2.150618)
			(end 4.842256 2.163064)
			(stroke
				(width 0.1524)
				(type default)
			)
			(layer "B.SilkS")
		)
		(fp_line
			(start 4.84378 -2.150618)
			(end 4.53898 -2.150618)
			(stroke
				(width 0.1524)
				(type default)
			)
			(layer "B.SilkS")
		)
		(fp_line
			(start 4.83108 2.150364)
			(end 4.447794 2.149348)
			(stroke
				(width 0.1524)
				(type default)
			)
			(layer "B.SilkS")
		)
		(fp_line
			(start 4.69138 -2.150618)
			(end 4.692396 2.161032)
			(stroke
				(width 0.1524)
				(type default)
			)
			(layer "B.SilkS")
		)
		(fp_line
			(start 4.53898 2.15011)
			(end 4.53898 -2.15011)
			(stroke
				(width 0.1524)
				(type default)
			)
			(layer "B.SilkS")
		)
		(fp_line
			(start 4.53898 -2.15011)
			(end -4.53898 -2.15011)
			(stroke
				(width 0.1524)
				(type default)
			)
			(layer "B.SilkS")
		)
		(fp_line
			(start 4.53898 -2.150618)
			(end 4.539742 2.152142)
			(stroke
				(width 0.1524)
				(type default)
			)
			(layer "B.SilkS")
		)
		(fp_line
			(start -4.53898 2.15011)
			(end 4.53898 2.15011)
			(stroke
				(width 0.1524)
				(type default)
			)
			(layer "B.SilkS")
		)
		(fp_line
			(start -4.53898 -2.15011)
			(end -4.53898 2.15011)
			(stroke
				(width 0.1524)
				(type default)
			)
			(layer "B.SilkS")
		)
		(fp_line
			(start 3.64998 2.15011)
			(end 3.64998 -2.15011)
			(stroke
				(width 0.1)
				(type default)
			)
			(layer "B.Fab")
		)
		(fp_line
			(start 3.64998 -2.15011)
			(end -3.64998 -2.15011)
			(stroke
				(width 0.1)
				(type default)
			)
			(layer "B.Fab")
		)
		(fp_line
			(start -3.64998 2.15011)
			(end 3.64998 2.15011)
			(stroke
				(width 0.1)
				(type default)
			)
			(layer "B.Fab")
		)
		(fp_line
			(start -3.64998 -2.15011)
			(end -3.64998 2.15011)
			(stroke
				(width 0.1)
				(type default)
			)
			(layer "B.Fab")
		)
		(fp_text user "+"
			(at 4.327652 -3.357118 180)
			(unlocked yes)
			(layer "B.SilkS")
			(effects
				(font
					(size 1.905 1.4224)
					(thickness 0.1524)
				)
				(justify left mirror)
			)
		)
		(fp_text user "-"
			(at -2.992374 -2.830068 180)
			(unlocked yes)
			(layer "B.SilkS")
			(effects
				(font
					(size 1.905 1.4224)
					(thickness 0.1524)
				)
				(justify left mirror)
			)
		)
		(fp_text user "+"
			(at 6.214872 -0.337058 180)
			(unlocked yes)
			(layer "B.Fab")
			(effects
				(font
					(size 1.905 1.4224)
					(thickness 0.1524)
				)
				(justify left mirror)
			)
		)
		(fp_text user "-"
			(at -4.313174 -0.094488 180)
			(unlocked yes)
			(layer "B.Fab")
			(effects
				(font
					(size 1.905 1.4224)
					(thickness 0.1524)
				)
				(justify left mirror)
			)
		)
		(pad "1" smd rect
			(at 3.199892 0)
			(size 2.413 2.8194)
			(layers "B.Cu" "B.Mask" "B.Paste")
			(net "P0V9_CPU1_RT3_2A")
		)
		(pad "2" smd rect
			(at -3.199892 0)
			(size 2.413 2.8194)
			(layers "B.Cu" "B.Mask" "B.Paste")
			(net "GND")
		)
	)
	(footprint ""
		(layer "B.Cu")
		(at 99.862386 -269.307564)
		(property "Reference" "C2358"
			(at 0 0 0)
			(layer "B.SilkS")
			(hide yes)
			(effects
				(font
					(size 1.27 1.27)
				)
				(justify mirror)
			)
		)
		(property "Value" ""
			(at 0 0 0)
			(layer "B.Fab")
			(effects
				(font
					(size 1.27 1.27)
				)
				(justify mirror)
			)
		)
		(duplicate_pad_numbers_are_jumpers no)
		(fp_line
			(start -0.7874 -0.4064)
			(end -0.7874 0.4064)
			(stroke
				(width 0.1524)
				(type default)
			)
			(layer "B.SilkS")
		)
		(fp_line
			(start -0.7874 0.4064)
			(end 0.7874 0.4064)
			(stroke
				(width 0.1524)
				(type default)
			)
			(layer "B.SilkS")
		)
		(fp_line
			(start 0.7874 -0.4064)
			(end -0.7874 -0.4064)
			(stroke
				(width 0.1524)
				(type default)
			)
			(layer "B.SilkS")
		)
		(fp_line
			(start 0.7874 0.4064)
			(end 0.7874 -0.4064)
			(stroke
				(width 0.1524)
				(type default)
			)
			(layer "B.SilkS")
		)
		(fp_line
			(start -0.67945 -0.3048)
			(end -0.67945 0.3048)
			(stroke
				(width 0.1)
				(type default)
			)
			(layer "B.Fab")
		)
		(fp_line
			(start -0.67945 0.3048)
			(end -0.120396 0.3048)
			(stroke
				(width 0.1)
				(type default)
			)
			(layer "B.Fab")
		)
		(fp_line
			(start -0.12065 -0.3048)
			(end -0.67945 -0.3048)
			(stroke
				(width 0.1)
				(type default)
			)
			(layer "B.Fab")
		)
		(fp_line
			(start -0.12065 -0.2794)
			(end -0.12065 -0.3048)
			(stroke
				(width 0.1)
				(type default)
			)
			(layer "B.Fab")
		)
		(fp_line
			(start -0.120396 0.2794)
			(end 0.12065 0.2794)
			(stroke
				(width 0.1)
				(type default)
			)
			(layer "B.Fab")
		)
		(fp_line
			(start -0.120396 0.3048)
			(end -0.120396 0.2794)
			(stroke
				(width 0.1)
				(type default)
			)
			(layer "B.Fab")
		)
		(fp_line
			(start 0.12065 -0.305054)
			(end 0.12065 -0.2794)
			(stroke
				(width 0.1)
				(type default)
			)
			(layer "B.Fab")
		)
		(fp_line
			(start 0.12065 -0.2794)
			(end -0.12065 -0.2794)
			(stroke
				(width 0.1)
				(type default)
			)
			(layer "B.Fab")
		)
		(fp_line
			(start 0.12065 0.2794)
			(end 0.12065 0.3048)
			(stroke
				(width 0.1)
				(type default)
			)
			(layer "B.Fab")
		)
		(fp_line
			(start 0.12065 0.3048)
			(end 0.67945 0.3048)
			(stroke
				(width 0.1)
				(type default)
			)
			(layer "B.Fab")
		)
		(fp_line
			(start 0.67945 -0.305054)
			(end 0.12065 -0.305054)
			(stroke
				(width 0.1)
				(type default)
			)
			(layer "B.Fab")
		)
		(fp_line
			(start 0.67945 0.3048)
			(end 0.67945 -0.305054)
			(stroke
				(width 0.1)
				(type default)
			)
			(layer "B.Fab")
		)
		(pad "1" smd circle
			(at 0.40005 0 180)
			(size 0 0)
			(layers "B.Cu" "B.Mask" "B.Paste")
			(net "PVDDCR_CPU1_P1")
		)
		(pad "2" smd circle
			(at -0.40005 0 180)
			(size 0 0)
			(layers "B.Cu" "B.Mask" "B.Paste")
			(net "GND")
		)
	)
	(footprint ""
		(layer "B.Cu")
		(at 371.551454 -255.84531)
		(property "Reference" "C2154"
			(at 0 0 0)
			(layer "B.SilkS")
			(hide yes)
			(effects
				(font
					(size 1.27 1.27)
				)
				(justify mirror)
			)
		)
		(property "Value" ""
			(at 0 0 0)
			(layer "B.Fab")
			(effects
				(font
					(size 1.27 1.27)
				)
				(justify mirror)
			)
		)
		(duplicate_pad_numbers_are_jumpers no)
		(fp_line
			(start -0.7874 -0.4064)
			(end -0.7874 0.4064)
			(stroke
				(width 0.1524)
				(type default)
			)
			(layer "B.SilkS")
		)
		(fp_line
			(start -0.7874 0.4064)
			(end 0.7874 0.4064)
			(stroke
				(width 0.1524)
				(type default)
			)
			(layer "B.SilkS")
		)
		(fp_line
			(start 0.7874 -0.4064)
			(end -0.7874 -0.4064)
			(stroke
				(width 0.1524)
				(type default)
			)
			(layer "B.SilkS")
		)
		(fp_line
			(start 0.7874 0.4064)
			(end 0.7874 -0.4064)
			(stroke
				(width 0.1524)
				(type default)
			)
			(layer "B.SilkS")
		)
		(fp_line
			(start -0.67945 -0.3048)
			(end -0.67945 0.3048)
			(stroke
				(width 0.1)
				(type default)
			)
			(layer "B.Fab")
		)
		(fp_line
			(start -0.67945 0.3048)
			(end -0.120396 0.3048)
			(stroke
				(width 0.1)
				(type default)
			)
			(layer "B.Fab")
		)
		(fp_line
			(start -0.12065 -0.3048)
			(end -0.67945 -0.3048)
			(stroke
				(width 0.1)
				(type default)
			)
			(layer "B.Fab")
		)
		(fp_line
			(start -0.12065 -0.2794)
			(end -0.12065 -0.3048)
			(stroke
				(width 0.1)
				(type default)
			)
			(layer "B.Fab")
		)
		(fp_line
			(start -0.120396 0.2794)
			(end 0.12065 0.2794)
			(stroke
				(width 0.1)
				(type default)
			)
			(layer "B.Fab")
		)
		(fp_line
			(start -0.120396 0.3048)
			(end -0.120396 0.2794)
			(stroke
				(width 0.1)
				(type default)
			)
			(layer "B.Fab")
		)
		(fp_line
			(start 0.12065 -0.305054)
			(end 0.12065 -0.2794)
			(stroke
				(width 0.1)
				(type default)
			)
			(layer "B.Fab")
		)
		(fp_line
			(start 0.12065 -0.2794)
			(end -0.12065 -0.2794)
			(stroke
				(width 0.1)
				(type default)
			)
			(layer "B.Fab")
		)
		(fp_line
			(start 0.12065 0.2794)
			(end 0.12065 0.3048)
			(stroke
				(width 0.1)
				(type default)
			)
			(layer "B.Fab")
		)
		(fp_line
			(start 0.12065 0.3048)
			(end 0.67945 0.3048)
			(stroke
				(width 0.1)
				(type default)
			)
			(layer "B.Fab")
		)
		(fp_line
			(start 0.67945 -0.305054)
			(end 0.12065 -0.305054)
			(stroke
				(width 0.1)
				(type default)
			)
			(layer "B.Fab")
		)
		(fp_line
			(start 0.67945 0.3048)
			(end 0.67945 -0.305054)
			(stroke
				(width 0.1)
				(type default)
			)
			(layer "B.Fab")
		)
		(pad "1" smd circle
			(at 0.40005 0 180)
			(size 0 0)
			(layers "B.Cu" "B.Mask" "B.Paste")
			(net "PVDDCR_SOC_P0")
		)
		(pad "2" smd circle
			(at -0.40005 0 180)
			(size 0 0)
			(layers "B.Cu" "B.Mask" "B.Paste")
			(net "GND")
		)
	)
	(footprint ""
		(layer "B.Cu")
		(at 116.878608 -386.766562 90)
		(property "Reference" "C452"
			(at 0 0 90)
			(layer "B.SilkS")
			(hide yes)
			(effects
				(font
					(size 1.27 1.27)
				)
				(justify mirror)
			)
		)
		(property "Value" ""
			(at 0 0 90)
			(layer "B.Fab")
			(effects
				(font
					(size 1.27 1.27)
				)
				(justify mirror)
			)
		)
		(duplicate_pad_numbers_are_jumpers no)
		(fp_line
			(start 0.299974 -0.150114)
			(end -0.299974 -0.150114)
			(stroke
				(width 0.1)
				(type default)
			)
			(layer "B.Fab")
		)
		(fp_line
			(start -0.299974 -0.150114)
			(end -0.299974 0.150114)
			(stroke
				(width 0.1)
				(type default)
			)
			(layer "B.Fab")
		)
		(fp_line
			(start 0.299974 0.150114)
			(end 0.299974 -0.150114)
			(stroke
				(width 0.1)
				(type default)
			)
			(layer "B.Fab")
		)
		(fp_line
			(start -0.299974 0.150114)
			(end 0.299974 0.150114)
			(stroke
				(width 0.1)
				(type default)
			)
			(layer "B.Fab")
		)
		(pad "1" smd rect
			(at 0.2667 0 270)
			(size 0.3048 0.381)
			(layers "B.Cu" "B.Mask" "B.Paste")
			(net "P0V9_CPU1_RT3_2A")
		)
		(pad "2" smd rect
			(at -0.2667 0 270)
			(size 0.3048 0.381)
			(layers "B.Cu" "B.Mask" "B.Paste")
			(net "GND")
		)
	)
	(footprint ""
		(layer "B.Cu")
		(at 181.013608 -126.833376 90)
		(property "Reference" "R253"
			(at 0 0 90)
			(layer "B.SilkS")
			(hide yes)
			(effects
				(font
					(size 1.27 1.27)
				)
				(justify mirror)
			)
		)
		(property "Value" ""
			(at 0 0 90)
			(layer "B.Fab")
			(effects
				(font
					(size 1.27 1.27)
				)
				(justify mirror)
			)
		)
		(duplicate_pad_numbers_are_jumpers no)
		(fp_line
			(start 0.7874 -0.4064)
			(end -0.7874 -0.4064)
			(stroke
				(width 0.1524)
				(type default)
			)
			(layer "B.SilkS")
		)
		(fp_line
			(start -0.7874 -0.4064)
			(end -0.7874 0.4064)
			(stroke
				(width 0.1524)
				(type default)
			)
			(layer "B.SilkS")
		)
		(fp_line
			(start 0.7874 0.4064)
			(end 0.7874 -0.4064)
			(stroke
				(width 0.1524)
				(type default)
			)
			(layer "B.SilkS")
		)
		(fp_line
			(start -0.7874 0.4064)
			(end 0.7874 0.4064)
			(stroke
				(width 0.1524)
				(type default)
			)
			(layer "B.SilkS")
		)
		(fp_line
			(start 0.67945 -0.305054)
			(end 0.12065 -0.305054)
			(stroke
				(width 0.1)
				(type default)
			)
			(layer "B.Fab")
		)
		(fp_line
			(start 0.12065 -0.305054)
			(end 0.12065 -0.2794)
			(stroke
				(width 0.1)
				(type default)
			)
			(layer "B.Fab")
		)
		(fp_line
			(start -0.12065 -0.3048)
			(end -0.67945 -0.3048)
			(stroke
				(width 0.1)
				(type default)
			)
			(layer "B.Fab")
		)
		(fp_line
			(start -0.67945 -0.3048)
			(end -0.67945 0.3048)
			(stroke
				(width 0.1)
				(type default)
			)
			(layer "B.Fab")
		)
		(fp_line
			(start 0.12065 -0.2794)
			(end -0.12065 -0.2794)
			(stroke
				(width 0.1)
				(type default)
			)
			(layer "B.Fab")
		)
		(fp_line
			(start -0.12065 -0.2794)
			(end -0.12065 -0.3048)
			(stroke
				(width 0.1)
				(type default)
			)
			(layer "B.Fab")
		)
		(fp_line
			(start 0.12065 0.2794)
			(end 0.12065 0.3048)
			(stroke
				(width 0.1)
				(type default)
			)
			(layer "B.Fab")
		)
		(fp_line
			(start -0.120396 0.2794)
			(end 0.12065 0.2794)
			(stroke
				(width 0.1)
				(type default)
			)
			(layer "B.Fab")
		)
		(fp_line
			(start 0.67945 0.3048)
			(end 0.67945 -0.305054)
			(stroke
				(width 0.1)
				(type default)
			)
			(layer "B.Fab")
		)
		(fp_line
			(start 0.12065 0.3048)
			(end 0.67945 0.3048)
			(stroke
				(width 0.1)
				(type default)
			)
			(layer "B.Fab")
		)
		(fp_line
			(start -0.120396 0.3048)
			(end -0.120396 0.2794)
			(stroke
				(width 0.1)
				(type default)
			)
			(layer "B.Fab")
		)
		(fp_line
			(start -0.67945 0.3048)
			(end -0.120396 0.3048)
			(stroke
				(width 0.1)
				(type default)
			)
			(layer "B.Fab")
		)
		(pad "1" smd circle
			(at 0.40005 0 270)
			(size 0 0)
			(layers "B.Cu" "B.Mask" "B.Paste")
			(net "CPU0_NV_SAVE_N")
		)
		(pad "2" smd circle
			(at -0.40005 0 270)
			(size 0 0)
			(layers "B.Cu" "B.Mask" "B.Paste")
			(net "FM_CPU0_NV_SAVE_N")
		)
	)
	(footprint ""
		(layer "B.Cu")
		(at 33.467294 -193.996564)
		(property "Reference" "R106"
			(at 0 0 0)
			(layer "B.SilkS")
			(hide yes)
			(effects
				(font
					(size 1.27 1.27)
				)
				(justify mirror)
			)
		)
		(property "Value" ""
			(at 0 0 0)
			(layer "B.Fab")
			(effects
				(font
					(size 1.27 1.27)
				)
				(justify mirror)
			)
		)
		(duplicate_pad_numbers_are_jumpers no)
		(fp_line
			(start -0.7874 -0.4064)
			(end -0.7874 0.4064)
			(stroke
				(width 0.1524)
				(type default)
			)
			(layer "B.SilkS")
		)
		(fp_line
			(start -0.7874 0.4064)
			(end 0.7874 0.4064)
			(stroke
				(width 0.1524)
				(type default)
			)
			(layer "B.SilkS")
		)
		(fp_line
			(start 0.7874 -0.4064)
			(end -0.7874 -0.4064)
			(stroke
				(width 0.1524)
				(type default)
			)
			(layer "B.SilkS")
		)
		(fp_line
			(start 0.7874 0.4064)
			(end 0.7874 -0.4064)
			(stroke
				(width 0.1524)
				(type default)
			)
			(layer "B.SilkS")
		)
		(fp_line
			(start -0.67945 -0.3048)
			(end -0.67945 0.3048)
			(stroke
				(width 0.1)
				(type default)
			)
			(layer "B.Fab")
		)
		(fp_line
			(start -0.67945 0.3048)
			(end -0.120396 0.3048)
			(stroke
				(width 0.1)
				(type default)
			)
			(layer "B.Fab")
		)
		(fp_line
			(start -0.12065 -0.3048)
			(end -0.67945 -0.3048)
			(stroke
				(width 0.1)
				(type default)
			)
			(layer "B.Fab")
		)
		(fp_line
			(start -0.12065 -0.2794)
			(end -0.12065 -0.3048)
			(stroke
				(width 0.1)
				(type default)
			)
			(layer "B.Fab")
		)
		(fp_line
			(start -0.120396 0.2794)
			(end 0.12065 0.2794)
			(stroke
				(width 0.1)
				(type default)
			)
			(layer "B.Fab")
		)
		(fp_line
			(start -0.120396 0.3048)
			(end -0.120396 0.2794)
			(stroke
				(width 0.1)
				(type default)
			)
			(layer "B.Fab")
		)
		(fp_line
			(start 0.12065 -0.305054)
			(end 0.12065 -0.2794)
			(stroke
				(width 0.1)
				(type default)
			)
			(layer "B.Fab")
		)
		(fp_line
			(start 0.12065 -0.2794)
			(end -0.12065 -0.2794)
			(stroke
				(width 0.1)
				(type default)
			)
			(layer "B.Fab")
		)
		(fp_line
			(start 0.12065 0.2794)
			(end 0.12065 0.3048)
			(stroke
				(width 0.1)
				(type default)
			)
			(layer "B.Fab")
		)
		(fp_line
			(start 0.12065 0.3048)
			(end 0.67945 0.3048)
			(stroke
				(width 0.1)
				(type default)
			)
			(layer "B.Fab")
		)
		(fp_line
			(start 0.67945 -0.305054)
			(end 0.12065 -0.305054)
			(stroke
				(width 0.1)
				(type default)
			)
			(layer "B.Fab")
		)
		(fp_line
			(start 0.67945 0.3048)
			(end 0.67945 -0.305054)
			(stroke
				(width 0.1)
				(type default)
			)
			(layer "B.Fab")
		)
		(pad "1" smd circle
			(at 0.40005 0 180)
			(size 0 0)
			(layers "B.Cu" "B.Mask" "B.Paste")
			(net "P3V3")
		)
		(pad "2" smd circle
			(at -0.40005 0 180)
			(size 0 0)
			(layers "B.Cu" "B.Mask" "B.Paste")
			(net "PWRGD_CHD_CPU1_DIMM")
		)
	)
	(footprint ""
		(layer "B.Cu")
		(at 10.808208 -138.93927 180)
		(property "Reference" "L17"
			(at 0 0 0)
			(layer "B.SilkS")
			(hide yes)
			(effects
				(font
					(size 1.27 1.27)
				)
				(justify mirror)
			)
		)
		(property "Value" ""
			(at 0 0 0)
			(layer "B.Fab")
			(effects
				(font
					(size 1.27 1.27)
				)
				(justify mirror)
			)
		)
		(duplicate_pad_numbers_are_jumpers no)
		(fp_line
			(start 1.63576 -0.8128)
			(end 1.63576 0.8128)
			(stroke
				(width 0.1524)
				(type default)
			)
			(layer "B.SilkS")
		)
		(fp_line
			(start 1.63576 -0.8128)
			(end -1.63576 -0.8128)
			(stroke
				(width 0.1524)
				(type default)
			)
			(layer "B.SilkS")
		)
		(fp_line
			(start -1.63576 0.8128)
			(end 1.63576 0.8128)
			(stroke
				(width 0.1524)
				(type default)
			)
			(layer "B.SilkS")
		)
		(fp_line
			(start -1.63576 -0.8128)
			(end -1.63576 0.8128)
			(stroke
				(width 0.1524)
				(type default)
			)
			(layer "B.SilkS")
		)
		(fp_line
			(start 1.56083 0.7366)
			(end 1.524 0.7366)
			(stroke
				(width 0.1)
				(type default)
			)
			(layer "B.Fab")
		)
		(fp_line
			(start 1.56083 -0.738632)
			(end 1.56083 0.7366)
			(stroke
				(width 0.1)
				(type default)
			)
			(layer "B.Fab")
		)
		(fp_line
			(start 1.524 0.7366)
			(end -1.524 0.7366)
			(stroke
				(width 0.1)
				(type default)
			)
			(layer "B.Fab")
		)
		(fp_line
			(start -1.524 0.7366)
			(end -1.560576 0.7366)
			(stroke
				(width 0.1)
				(type default)
			)
			(layer "B.Fab")
		)
		(fp_line
			(start -1.560576 0.7366)
			(end -1.560576 -0.738632)
			(stroke
				(width 0.1)
				(type default)
			)
			(layer "B.Fab")
		)
		(fp_line
			(start -1.560576 -0.738632)
			(end 1.56083 -0.738632)
			(stroke
				(width 0.1)
				(type default)
			)
			(layer "B.Fab")
		)
		(pad "1" smd rect
			(at 0.94996 0 180)
			(size 1.1176 1.3716)
			(layers "B.Cu" "B.Mask" "B.Paste")
			(net "P3V3_AUX")
		)
		(pad "2" smd rect
			(at -0.94996 0 180)
			(size 1.1176 1.3716)
			(layers "B.Cu" "B.Mask" "B.Paste")
			(net "VFG3P3_CLK_GEN")
		)
	)
)
